FILE_TYPE = MULTI_PHYS_TABLE;

PART 'NC7SB3157'

{========================================================================================}
:VALUE          | MANUF_PN       | PACK_TYPE | MATERIAL | PART_NUMBER    = STANDARD         | LIFECYCLE        | ENVCOMP | PART_NUMBER   | JEDEC_TYPE | CLASS | DESCRIPTION                   | HEIGHT   | COMPONENT_TYPE | LEAD_LENGTH | LPID | DAY        ;
{========================================================================================}
 'NC7SB3157P6X' | 'NC7SB3157P6X' | 'SMLF'    | 'IC'     | 'ALSB3157000'(!) = 'End of Design'  | 'Comp-Approve'   | 'YES'   | 'ALSB3157000' |'SC70-6'| 'IC'  | 'IC(6P) NC7SB3157P6X(SC70-6)' | '.044IN' | 'SMALLSMT'     | ''          | ''   | '20100709'
 'NC7SB3157P6X' | 'NC7SB3157P6X' | 'SMLF'    | 'EMPTY'  | 'ALSB3157000'(!) = 'End of Design'  | 'Comp-Approve'   | 'YES'   | 'ALSB3157000' |'SC70-6'| 'IO'  | 'IC(6P) NC7SB3157P6X(SC70-6)' | '.044IN' | 'SMALLSMT'     | ''          | ''   | '20100709'

END_PART

END.

